(kicad_pcb
	(version 20260206)
	(generator "pcbnew")
	(generator_version "10.0")
	(general
		(thickness 1.6)
		(legacy_teardrops no)
	)
	(paper "A4")
	(title_block
		(title "Bryce Canyon_R.DPB_16317-1_OCP.brd")
		(comment 1 "Bryce Canyon / footprints 1361-1368 of 2099")
	)
	(layers
		(0 "F.Cu" signal "TOP")
		(4 "In1.Cu" signal "L2GND")
		(6 "In2.Cu" signal "L3")
		(8 "In3.Cu" signal "L4VCC")
		(10 "In4.Cu" signal "L5VCC")
		(12 "In5.Cu" signal "L6")
		(14 "In6.Cu" signal "L7GND")
		(2 "B.Cu" signal "BOTTOM")
		(9 "F.Adhes" user "F.Adhesive")
		(11 "B.Adhes" user "B.Adhesive")
		(13 "F.Paste" user "Package Geometry/Pastemask Top")
		(15 "B.Paste" user "Package Geometry/Pastemask Bottom")
		(5 "F.SilkS" user "Ref Des/Silkscreen Top")
		(7 "B.SilkS" user "Ref Des/Silkscreen Bottom")
		(1 "F.Mask" user "Board Geometry/Soldermask Top")
		(3 "B.Mask" user "Board Geometry/Soldermask Bottom")
		(17 "Dwgs.User" user "User.Drawings")
		(19 "Cmts.User" user "User.Comments")
		(21 "Eco1.User" user "User.Eco1")
		(23 "Eco2.User" user "User.Eco2")
		(25 "Edge.Cuts" user "Board Geometry/Outline")
		(27 "Margin" user)
		(31 "F.CrtYd" user "Package Geometry/Place Bound Top")
		(29 "B.CrtYd" user "Package Geometry/Place Bound Bottom")
		(35 "F.Fab" user "Ref Des/Assembly Top")
		(33 "B.Fab" user "Ref Des/Assembly Bottom")
	)
	(footprint ""
		(layer "F.Cu")
		(at 265.586972 -353.463606 -90)
		(property "Reference" "R153"
			(at 0 0 270)
			(layer "F.SilkS")
			(hide yes)
			(effects
				(font
					(size 1.27 1.27)
				)
			)
		)
		(property "Value" "0R5J-5-GP"
			(at 0 -8.9535 270)
			(unlocked yes)
			(layer "F.Fab")
			(hide yes)
			(effects
				(font
					(size 1.27 1.016)
					(thickness 0.1524)
				)
			)
		)
		(property "Device Type" "R805H24"
			(at 0 -10.6299 270)
			(unlocked yes)
			(layer "F.Fab")
			(hide yes)
			(effects
				(font
					(size 1.27 1.016)
					(thickness 0.1524)
				)
			)
		)
		(duplicate_pad_numbers_are_jumpers no)
		(fp_line
			(start -0.889 1.7018)
			(end 0.889 1.7018)
			(stroke
				(width 0.1524)
				(type default)
			)
			(layer "F.SilkS")
		)
		(fp_line
			(start 0.889 1.7018)
			(end 0.889 -0.508)
			(stroke
				(width 0.1524)
				(type default)
			)
			(layer "F.SilkS")
		)
		(fp_line
			(start -0.889 0.0762)
			(end -0.889 1.7018)
			(stroke
				(width 0.1524)
				(type default)
			)
			(layer "F.SilkS")
		)
		(fp_line
			(start -0.889 -1.7018)
			(end -0.889 0.2794)
			(stroke
				(width 0.1524)
				(type default)
			)
			(layer "F.SilkS")
		)
		(fp_line
			(start 0.889 -1.7018)
			(end 0.889 -0.381)
			(stroke
				(width 0.1524)
				(type default)
			)
			(layer "F.SilkS")
		)
		(fp_line
			(start 0.889 -1.7018)
			(end -0.889 -1.7018)
			(stroke
				(width 0.1524)
				(type default)
			)
			(layer "F.SilkS")
		)
		(fp_poly
			(pts
				(xy 0.9652 -1.778) (xy 0.9652 1.778) (xy -0.9652 1.778) (xy -0.9652 -1.778)
			)
			(stroke
				(width 0)
				(type default)
			)
			(fill no)
			(layer "F.CrtYd")
		)
		(fp_rect
			(start -0.9652 1.778)
			(end 0.9652 -1.778)
			(stroke
				(width 0)
				(type default)
			)
			(fill no)
			(layer "F.Fab")
		)
		(pad "1" smd rect
			(at 0 -0.9652 270)
			(size 1.397 1.143)
			(layers "F.Cu" "F.Mask" "F.Paste")
			(net "MB3_CM_GATE_R")
		)
		(pad "2" smd rect
			(at 0 0.9652 270)
			(size 1.397 1.143)
			(layers "F.Cu" "F.Mask" "F.Paste")
			(net "MB3_CM_GATE_C")
		)
	)
	(footprint ""
		(layer "F.Cu")
		(at 55.499 -42.291)
		(property "Reference" "C360"
			(at 0 0 0)
			(layer "F.SilkS")
			(hide yes)
			(effects
				(font
					(size 1.27 1.27)
				)
			)
		)
		(property "Value" "SC4D7U25V5KX-1-GP"
			(at -0.0762 -6.1214 0)
			(unlocked yes)
			(layer "F.Fab")
			(hide yes)
			(effects
				(font
					(size 1.016 1.016)
					(thickness 0.1524)
				)
			)
		)
		(property "Device Type" "C805H58"
			(at -0.0762 -8.1534 0)
			(unlocked yes)
			(layer "F.Fab")
			(hide yes)
			(effects
				(font
					(size 1.016 1.016)
					(thickness 0.1524)
				)
			)
		)
		(duplicate_pad_numbers_are_jumpers no)
		(fp_line
			(start 0.635 0)
			(end -0.635 0)
			(stroke
				(width 0.508)
				(type default)
			)
			(layer "F.SilkS")
		)
		(fp_rect
			(start -0.9652 1.778)
			(end 0.9652 -1.778)
			(stroke
				(width 0)
				(type default)
			)
			(fill no)
			(layer "F.CrtYd")
		)
		(fp_poly
			(pts
				(xy -0.9652 -1.778) (xy 0.9652 -1.778) (xy 0.9652 1.778) (xy -0.9652 1.778)
			)
			(stroke
				(width 0)
				(type default)
			)
			(fill no)
			(layer "F.Fab")
		)
		(pad "1" smd rect
			(at 0 -0.9652)
			(size 1.397 1.143)
			(layers "F.Cu" "F.Mask" "F.Paste")
			(net "P12V_HDD25")
		)
		(pad "2" smd rect
			(at 0 0.9652)
			(size 1.397 1.143)
			(layers "F.Cu" "F.Mask" "F.Paste")
			(net "GND")
		)
	)
	(footprint ""
		(layer "F.Cu")
		(at 117.0686 -246.1768 -90)
		(property "Reference" "R214"
			(at 0 0 270)
			(layer "F.SilkS")
			(hide yes)
			(effects
				(font
					(size 1.27 1.27)
				)
			)
		)
		(property "Value" "0R2J-2-GP"
			(at 0.064008 -3.993896 270)
			(unlocked yes)
			(layer "F.Fab")
			(hide yes)
			(effects
				(font
					(size 1.016 1.016)
					(thickness 0.1524)
				)
			)
		)
		(property "Device Type" "R402H16"
			(at 0.064008 -5.517896 270)
			(unlocked yes)
			(layer "F.Fab")
			(hide yes)
			(effects
				(font
					(size 1.016 1.016)
					(thickness 0.1524)
				)
			)
		)
		(duplicate_pad_numbers_are_jumpers no)
		(fp_line
			(start -0.508 -0.9398)
			(end -0.508 0.9398)
			(stroke
				(width 0.1524)
				(type default)
			)
			(layer "F.SilkS")
		)
		(fp_line
			(start 0.508 -0.9398)
			(end -0.508 -0.9398)
			(stroke
				(width 0.1524)
				(type default)
			)
			(layer "F.SilkS")
		)
		(fp_rect
			(start -0.508 0.9398)
			(end 0.508 -0.9398)
			(stroke
				(width 0)
				(type default)
			)
			(fill no)
			(layer "F.CrtYd")
		)
		(fp_rect
			(start -0.508 0.9398)
			(end 0.508 -0.9398)
			(stroke
				(width 0)
				(type default)
			)
			(fill no)
			(layer "F.Fab")
		)
		(pad "1" smd custom
			(at 0 -0.4445 270)
			(size 0.1397 0.1397)
			(layers "F.Cu" "F.Mask" "F.Paste")
			(net "DRIVE_B_3_PWR")
			(options
				(clearance outline)
				(anchor circle)
			)
			(primitives
				(gr_poly
					(pts
						(arc
							(start -0.1778 -0.2794)
							(mid -0.249642 -0.249642)
							(end -0.2794 -0.1778)
						)
						(arc
							(start -0.2794 0.1778)
							(mid -0.249642 0.249642)
							(end -0.1778 0.2794)
						)
						(arc
							(start 0.1778 0.2794)
							(mid 0.249642 0.249642)
							(end 0.2794 0.1778)
						)
						(arc
							(start 0.2794 -0.1778)
							(mid 0.249642 -0.249642)
							(end 0.1778 -0.2794)
						)
					)
					(width 0)
					(fill yes)
				)
			)
		)
		(pad "2" smd custom
			(at 0 0.4445 270)
			(size 0.1397 0.1397)
			(layers "F.Cu" "F.Mask" "F.Paste")
			(net "SW_PWR_R_HDD3")
			(options
				(clearance outline)
				(anchor circle)
			)
			(primitives
				(gr_poly
					(pts
						(arc
							(start -0.1778 -0.2794)
							(mid -0.249642 -0.249642)
							(end -0.2794 -0.1778)
						)
						(arc
							(start -0.2794 0.1778)
							(mid -0.249642 0.249642)
							(end -0.1778 0.2794)
						)
						(arc
							(start 0.1778 0.2794)
							(mid 0.249642 0.249642)
							(end 0.2794 0.1778)
						)
						(arc
							(start 0.2794 -0.1778)
							(mid 0.249642 -0.249642)
							(end 0.1778 -0.2794)
						)
					)
					(width 0)
					(fill yes)
				)
			)
		)
	)
	(footprint ""
		(layer "F.Cu")
		(at 352.3488 -31.6484 180)
		(property "Reference" "R783"
			(at 0 0 180)
			(layer "F.SilkS")
			(hide yes)
			(effects
				(font
					(size 1.27 1.27)
				)
			)
		)
		(property "Value" "10KR2F-2-GP"
			(at 0.064008 -3.993896 180)
			(unlocked yes)
			(layer "F.Fab")
			(hide yes)
			(effects
				(font
					(size 1.016 1.016)
					(thickness 0.1524)
				)
			)
		)
		(property "Device Type" "R402H16"
			(at 0.064008 -5.517896 180)
			(unlocked yes)
			(layer "F.Fab")
			(hide yes)
			(effects
				(font
					(size 1.016 1.016)
					(thickness 0.1524)
				)
			)
		)
		(duplicate_pad_numbers_are_jumpers no)
		(fp_line
			(start 0.508 -0.9398)
			(end -0.508 -0.9398)
			(stroke
				(width 0.1524)
				(type default)
			)
			(layer "F.SilkS")
		)
		(fp_line
			(start -0.508 -0.9398)
			(end -0.508 0.9398)
			(stroke
				(width 0.1524)
				(type default)
			)
			(layer "F.SilkS")
		)
		(fp_rect
			(start -0.508 0.9398)
			(end 0.508 -0.9398)
			(stroke
				(width 0)
				(type default)
			)
			(fill no)
			(layer "F.CrtYd")
		)
		(fp_rect
			(start -0.508 0.9398)
			(end 0.508 -0.9398)
			(stroke
				(width 0)
				(type default)
			)
			(fill no)
			(layer "F.Fab")
		)
		(pad "1" smd custom
			(at 0 -0.4445 180)
			(size 0.1397 0.1397)
			(layers "F.Cu" "F.Mask" "F.Paste")
			(net "P3V3_STBY_B")
			(options
				(clearance outline)
				(anchor circle)
			)
			(primitives
				(gr_poly
					(pts
						(arc
							(start -0.1778 -0.2794)
							(mid -0.249642 -0.249642)
							(end -0.2794 -0.1778)
						)
						(arc
							(start -0.2794 0.1778)
							(mid -0.249642 0.249642)
							(end -0.1778 0.2794)
						)
						(arc
							(start 0.1778 0.2794)
							(mid 0.249642 0.249642)
							(end 0.2794 0.1778)
						)
						(arc
							(start 0.2794 -0.1778)
							(mid 0.249642 -0.249642)
							(end 0.1778 -0.2794)
						)
					)
					(width 0)
					(fill yes)
				)
			)
		)
		(pad "2" smd custom
			(at 0 0.4445 180)
			(size 0.1397 0.1397)
			(layers "F.Cu" "F.Mask" "F.Paste")
			(net "HDD_PRSNT_31")
			(options
				(clearance outline)
				(anchor circle)
			)
			(primitives
				(gr_poly
					(pts
						(arc
							(start -0.1778 -0.2794)
							(mid -0.249642 -0.249642)
							(end -0.2794 -0.1778)
						)
						(arc
							(start -0.2794 0.1778)
							(mid -0.249642 0.249642)
							(end -0.1778 0.2794)
						)
						(arc
							(start 0.1778 0.2794)
							(mid 0.249642 0.249642)
							(end 0.2794 0.1778)
						)
						(arc
							(start 0.2794 -0.1778)
							(mid 0.249642 -0.249642)
							(end 0.1778 -0.2794)
						)
					)
					(width 0)
					(fill yes)
				)
			)
		)
	)
	(footprint ""
		(layer "F.Cu")
		(at 190.258954 -18.750026 -90)
		(property "Reference" "VIA60"
			(at 0 0 270)
			(layer "F.SilkS")
			(hide yes)
			(effects
				(font
					(size 1.27 1.27)
				)
			)
		)
		(property "Value" "100OHM-8L-2D36MM-L16-GP"
			(at -3.4036 -0.4572 270)
			(unlocked yes)
			(layer "F.Fab")
			(hide yes)
			(effects
				(font
					(size 1.016 1.016)
					(thickness 0.1524)
				)
			)
		)
		(property "Device Type" "VIA-PCIE-4P-427097"
			(at -3.4036 -1.9812 270)
			(unlocked yes)
			(layer "F.Fab")
			(hide yes)
			(effects
				(font
					(size 1.016 1.016)
					(thickness 0.1524)
				)
			)
		)
		(duplicate_pad_numbers_are_jumpers no)
		(fp_rect
			(start -2.1336 0.4826)
			(end 2.1336 -0.4826)
			(stroke
				(width 0)
				(type default)
			)
			(fill no)
			(layer "F.CrtYd")
		)
		(fp_rect
			(start -2.1336 0.4826)
			(end 2.1336 -0.4826)
			(stroke
				(width 0)
				(type default)
			)
			(fill no)
			(layer "F.Fab")
		)
		(pad "1" thru_hole circle
			(at -1.651 0 270)
			(size 0.508 0.508)
			(drill 0.254)
			(layers "*.Cu" "*.Mask")
			(remove_unused_layers no)
			(net "GND")
			(clearance 0.2286)
			(thermal_gap 0.2286)
		)
		(pad "2" thru_hole circle
			(at -0.635 0 270)
			(size 0.508 0.508)
			(drill 0.254)
			(layers "*.Cu" "*.Mask")
			(remove_unused_layers no)
			(net "PHY_DRV_B_TO_SCC_B_29_DP")
			(clearance 0.2286)
			(thermal_gap 0.2286)
		)
		(pad "3" thru_hole circle
			(at 0.635 0 270)
			(size 0.508 0.508)
			(drill 0.254)
			(layers "*.Cu" "*.Mask")
			(remove_unused_layers no)
			(net "PHY_DRV_B_TO_SCC_B_29_DN")
			(clearance 0.2286)
			(thermal_gap 0.2286)
		)
		(pad "4" thru_hole circle
			(at 1.651 0 270)
			(size 0.508 0.508)
			(drill 0.254)
			(layers "*.Cu" "*.Mask")
			(remove_unused_layers no)
			(net "GND")
			(clearance 0.2286)
			(thermal_gap 0.2286)
		)
	)
	(footprint ""
		(layer "F.Cu")
		(at 14.859 -145.796)
		(property "Reference" "Q48"
			(at 0 0 0)
			(layer "F.SilkS")
			(hide yes)
			(effects
				(font
					(size 1.27 1.27)
				)
			)
		)
		(property "Value" "AO4407AL-GP"
			(at -3.707384 -1.5367 0)
			(unlocked yes)
			(layer "F.Fab")
			(hide yes)
			(effects
				(font
					(size 1.016 1.016)
					(thickness 0.1524)
				)
			)
		)
		(property "Device Type" "SOIC8H69"
			(at -3.707384 -3.0607 0)
			(unlocked yes)
			(layer "F.Fab")
			(hide yes)
			(effects
				(font
					(size 1.016 1.016)
					(thickness 0.1524)
				)
			)
		)
		(duplicate_pad_numbers_are_jumpers no)
		(fp_line
			(start -2.7432 -1.4224)
			(end -2.7432 1.4224)
			(stroke
				(width 0.1524)
				(type default)
			)
			(layer "F.SilkS")
		)
		(fp_line
			(start -2.7432 1.4224)
			(end -2.6416 1.4224)
			(stroke
				(width 0.1524)
				(type default)
			)
			(layer "F.SilkS")
		)
		(fp_line
			(start -2.7432 1.4224)
			(end 2.1336 1.4224)
			(stroke
				(width 0.1524)
				(type default)
			)
			(layer "F.SilkS")
		)
		(fp_line
			(start -2.7178 -0.508)
			(end -2.1844 -0.0508)
			(stroke
				(width 0.1524)
				(type default)
			)
			(layer "F.SilkS")
		)
		(fp_line
			(start -2.6289 3.4417)
			(end -2.6289 1.4732)
			(stroke
				(width 0.381)
				(type default)
			)
			(layer "F.SilkS")
		)
		(fp_line
			(start -2.1844 -0.0508)
			(end -2.7178 0.508)
			(stroke
				(width 0.1524)
				(type default)
			)
			(layer "F.SilkS")
		)
		(fp_line
			(start 2.1336 -1.4224)
			(end -2.7432 -1.4224)
			(stroke
				(width 0.1524)
				(type default)
			)
			(layer "F.SilkS")
		)
		(fp_line
			(start 2.1336 1.4224)
			(end 2.1336 -1.4224)
			(stroke
				(width 0.1524)
				(type default)
			)
			(layer "F.SilkS")
		)
		(fp_poly
			(pts
				(xy -2.2098 -1.4224) (xy -2.2098 1.4224) (xy 2.2098 1.4224) (xy 2.2098 -1.4224)
			)
			(stroke
				(width 0)
				(type default)
			)
			(fill yes)
			(layer "F.SilkS")
		)
		(fp_rect
			(start -2.450084 2.999994)
			(end 2.450084 -2.999994)
			(stroke
				(width 0)
				(type default)
			)
			(fill no)
			(layer "F.CrtYd")
		)
		(fp_poly
			(pts
				(xy -2.8194 3.6322) (xy -2.8194 -3.6322) (xy 2.8194 -3.6322) (xy 2.8194 1.18364) (xy 2.450084 1.18364)
				(xy 2.450084 -2.999994) (xy -2.450084 -2.999994) (xy -2.450084 2.999994) (xy 2.450084 2.999994)
				(xy 2.450084 1.18618) (xy 2.8194 1.18618) (xy 2.8194 3.6322)
			)
			(stroke
				(width 0)
				(type default)
			)
			(fill no)
			(layer "F.CrtYd")
		)
		(fp_rect
			(start -2.8194 3.6322)
			(end 2.8194 -3.6322)
			(stroke
				(width 0)
				(type default)
			)
			(fill no)
			(layer "F.Fab")
		)
		(pad "1" smd rect
			(at -1.905 2.54)
			(size 0.635 1.651)
			(layers "F.Cu" "F.Mask" "F.Paste")
			(net "P12V_B")
		)
		(pad "2" smd rect
			(at -0.635 2.54)
			(size 0.635 1.651)
			(layers "F.Cu" "F.Mask" "F.Paste")
			(net "P12V_B")
		)
		(pad "3" smd rect
			(at 0.635 2.54)
			(size 0.635 1.651)
			(layers "F.Cu" "F.Mask" "F.Paste")
			(net "P12V_B")
		)
		(pad "4" smd rect
			(at 1.905 2.54)
			(size 0.635 1.651)
			(layers "F.Cu" "F.Mask" "F.Paste")
			(net "SW_HDD_N12")
		)
		(pad "5" smd rect
			(at 1.905 -2.54)
			(size 0.635 1.651)
			(layers "F.Cu" "F.Mask" "F.Paste")
			(net "P12V_HDD12")
		)
		(pad "6" smd rect
			(at 0.635 -2.54)
			(size 0.635 1.651)
			(layers "F.Cu" "F.Mask" "F.Paste")
			(net "P12V_HDD12")
		)
		(pad "7" smd rect
			(at -0.635 -2.54)
			(size 0.635 1.651)
			(layers "F.Cu" "F.Mask" "F.Paste")
			(net "P12V_HDD12")
		)
		(pad "8" smd rect
			(at -1.905 -2.54)
			(size 0.635 1.651)
			(layers "F.Cu" "F.Mask" "F.Paste")
			(net "P12V_HDD12")
		)
	)
	(footprint ""
		(layer "F.Cu")
		(at 477.0628 -153.1366)
		(property "Reference" "TP136"
			(at 0 0 0)
			(layer "F.SilkS")
			(hide yes)
			(effects
				(font
					(size 1.27 1.27)
				)
			)
		)
		(property "Value" "*"
			(at -0.0508 -1.6764 0)
			(unlocked yes)
			(layer "F.Fab")
			(hide yes)
			(effects
				(font
					(size 1.016 1.016)
					(thickness 0.1524)
				)
			)
		)
		(property "Device Type" "TPAD32"
			(at -0.0508 -3.2004 0)
			(unlocked yes)
			(layer "F.Fab")
			(hide yes)
			(effects
				(font
					(size 1.016 1.016)
					(thickness 0.1524)
				)
			)
		)
		(duplicate_pad_numbers_are_jumpers no)
		(fp_poly
			(pts
				(arc
					(start 0.4064 0)
					(mid -0.4064 0)
					(end 0.4064 0)
				)
			)
			(stroke
				(width 0)
				(type default)
			)
			(fill no)
			(layer "F.CrtYd")
		)
		(fp_poly
			(pts
				(arc
					(start 0.7112 0)
					(mid -0.7112 0)
					(end 0.7112 0)
				)
			)
			(stroke
				(width 0)
				(type default)
			)
			(fill no)
			(layer "F.Fab")
		)
		(pad "1" smd circle
			(at 0 0)
			(size 0.8128 0.8128)
			(layers "F.Cu" "F.Mask" "F.Paste")
			(net "ACT_HDD_23")
		)
	)
	(footprint ""
		(layer "F.Cu")
		(at 118.364 -148.209)
		(property "Reference" "R414"
			(at 0 0 0)
			(layer "F.SilkS")
			(hide yes)
			(effects
				(font
					(size 1.27 1.27)
				)
			)
		)
		(property "Value" "2R6F-GP"
			(at -0.0508 -4.8514 0)
			(unlocked yes)
			(layer "F.Fab")
			(hide yes)
			(effects
				(font
					(size 1.016 1.016)
					(thickness 0.1524)
				)
			)
		)
		(property "Device Type" "R1206H26"
			(at 0 -6.3754 0)
			(unlocked yes)
			(layer "F.Fab")
			(hide yes)
			(effects
				(font
					(size 1.016 1.016)
					(thickness 0.1524)
				)
			)
		)
		(duplicate_pad_numbers_are_jumpers no)
		(fp_line
			(start -1.016 -2.2352)
			(end 1.016 -2.2352)
			(stroke
				(width 0.1524)
				(type default)
			)
			(layer "F.SilkS")
		)
		(fp_line
			(start -1.016 2.2352)
			(end -1.016 -2.2352)
			(stroke
				(width 0.1524)
				(type default)
			)
			(layer "F.SilkS")
		)
		(fp_line
			(start 1.016 -2.2352)
			(end 1.016 2.2352)
			(stroke
				(width 0.1524)
				(type default)
			)
			(layer "F.SilkS")
		)
		(fp_line
			(start 1.016 2.2352)
			(end -1.016 2.2352)
			(stroke
				(width 0.1524)
				(type default)
			)
			(layer "F.SilkS")
		)
		(fp_rect
			(start -1.0922 2.3114)
			(end 1.0922 -2.3114)
			(stroke
				(width 0)
				(type default)
			)
			(fill no)
			(layer "F.CrtYd")
		)
		(fp_poly
			(pts
				(xy -1.0922 -2.3114) (xy 1.0922 -2.3114) (xy 1.0922 2.3114) (xy -1.0922 2.3114)
			)
			(stroke
				(width 0)
				(type default)
			)
			(fill no)
			(layer "F.Fab")
		)
		(pad "1" smd rect
			(at 0 -1.397)
			(size 1.651 1.27)
			(layers "F.Cu" "F.Mask" "F.Paste")
			(net "P5V_HDD15")
		)
		(pad "2" smd rect
			(at 0 1.397)
			(size 1.651 1.27)
			(layers "F.Cu" "F.Mask" "F.Paste")
			(net "5V_PRE_15")
		)
	)
)
